# T6G (Grand Teton) — schematic netlist excerpt (pin names and nets, part order shuffled) for the footprints in the layout excerpt that follows; sources: Cadence DE-HDL packaged netlist, KiCad conversion of 04192023_DAF0TMB3IC0_F0TG_MB_C_brd_V02_OCP.brd

C6557  Q_CAP_DIFFBUS  DIFF BUS_0.22UF 6.3V 20% X6S  pkg C0201  page 286 : \1\ = P5E_CPU0_P1_TX_BUF_C_DP<12> ; \2\ = P5E_CPU0_P1_TX_BUF_DP<12>
R6034  Q_RES  1K 1% CHIP  pkg 0402LF  page 150 : A = P3V3_AUX ; B = SCM_ROT_CPU_RST_R_N
R1394  Q_RES  4.7K 5% CHIP  pkg 0201LF  page 185 : A = P1V8_CPU1_RT_1D ; B = SMB_RT_CPU1_P1_ROM_MUX_2D_R_SCL

(kicad_pcb
	(version 20260206)
	(generator "pcbnew")
	(generator_version "10.0")
	(general
		(thickness 1.6)
		(legacy_teardrops no)
	)
	(paper "A4")
	(title_block
		(title "04192023_DAF0TMB3IC0_F0TG_MB_C_brd_V02_OCP.brd")
		(comment 1 "Grand Teton / footprints 7093-7095 of 8354")
	)
	(layers
		(0 "F.Cu" signal "TOP")
		(4 "In1.Cu" signal "GND")
		(6 "In2.Cu" signal "IN1")
		(8 "In3.Cu" signal "GND1")
		(10 "In4.Cu" signal "IN2")
		(12 "In5.Cu" signal "GND2")
		(14 "In6.Cu" signal "IN3")
		(16 "In7.Cu" signal "GND3")
		(18 "In8.Cu" signal "VCC")
		(20 "In9.Cu" signal "VCC1")
		(22 "In10.Cu" signal "GND4")
		(24 "In11.Cu" signal "IN4")
		(26 "In12.Cu" signal "GND5")
		(28 "In13.Cu" signal "IN5")
		(30 "In14.Cu" signal "GND6")
		(32 "In15.Cu" signal "IN6")
		(34 "In16.Cu" signal "GND7")
		(2 "B.Cu" signal "BOTTOM")
		(9 "F.Adhes" user "F.Adhesive")
		(11 "B.Adhes" user "B.Adhesive")
		(13 "F.Paste" user "Package Geometry/Pastemask Top")
		(15 "B.Paste" user "Package Geometry/Pastemask Bottom")
		(5 "F.SilkS" user "Ref Des/Silkscreen Top")
		(7 "B.SilkS" user "Ref Des/Silkscreen Bottom")
		(1 "F.Mask" user "Board Geometry/Soldermask Top")
		(3 "B.Mask" user "Board Geometry/Soldermask Bottom")
		(17 "Dwgs.User" user "User.Drawings")
		(19 "Cmts.User" user "User.Comments")
		(21 "Eco1.User" user "User.Eco1")
		(23 "Eco2.User" user "User.Eco2")
		(25 "Edge.Cuts" user "Board Geometry/Outline")
		(27 "Margin" user)
		(31 "F.CrtYd" user "Package Geometry/Place Bound Top")
		(29 "B.CrtYd" user "Package Geometry/Place Bound Bottom")
		(35 "F.Fab" user "Ref Des/Assembly Top")
		(33 "B.Fab" user "Ref Des/Assembly Bottom")
	)
	(footprint ""
		(layer "B.Cu")
		(at 138.7729 -9.03859 90)
		(property "Reference" "R6034"
			(at 0 0 90)
			(layer "B.SilkS")
			(hide yes)
			(effects
				(font
					(size 1.27 1.27)
				)
				(justify mirror)
			)
		)
		(property "Value" ""
			(at 0 0 90)
			(layer "B.Fab")
			(effects
				(font
					(size 1.27 1.27)
				)
				(justify mirror)
			)
		)
		(duplicate_pad_numbers_are_jumpers no)
		(fp_line
			(start 0.7874 -0.4064)
			(end -0.7874 -0.4064)
			(stroke
				(width 0.1524)
				(type default)
			)
			(layer "B.SilkS")
		)
		(fp_line
			(start -0.7874 -0.4064)
			(end -0.7874 0.4064)
			(stroke
				(width 0.1524)
				(type default)
			)
			(layer "B.SilkS")
		)
		(fp_line
			(start 0.7874 0.4064)
			(end 0.7874 -0.4064)
			(stroke
				(width 0.1524)
				(type default)
			)
			(layer "B.SilkS")
		)
		(fp_line
			(start -0.7874 0.4064)
			(end 0.7874 0.4064)
			(stroke
				(width 0.1524)
				(type default)
			)
			(layer "B.SilkS")
		)
		(fp_line
			(start 0.67945 -0.305054)
			(end 0.12065 -0.305054)
			(stroke
				(width 0.1)
				(type default)
			)
			(layer "B.Fab")
		)
		(fp_line
			(start 0.12065 -0.305054)
			(end 0.12065 -0.2794)
			(stroke
				(width 0.1)
				(type default)
			)
			(layer "B.Fab")
		)
		(fp_line
			(start -0.12065 -0.3048)
			(end -0.67945 -0.3048)
			(stroke
				(width 0.1)
				(type default)
			)
			(layer "B.Fab")
		)
		(fp_line
			(start -0.67945 -0.3048)
			(end -0.67945 0.3048)
			(stroke
				(width 0.1)
				(type default)
			)
			(layer "B.Fab")
		)
		(fp_line
			(start 0.12065 -0.2794)
			(end -0.12065 -0.2794)
			(stroke
				(width 0.1)
				(type default)
			)
			(layer "B.Fab")
		)
		(fp_line
			(start -0.12065 -0.2794)
			(end -0.12065 -0.3048)
			(stroke
				(width 0.1)
				(type default)
			)
			(layer "B.Fab")
		)
		(fp_line
			(start 0.12065 0.2794)
			(end 0.12065 0.3048)
			(stroke
				(width 0.1)
				(type default)
			)
			(layer "B.Fab")
		)
		(fp_line
			(start -0.120396 0.2794)
			(end 0.12065 0.2794)
			(stroke
				(width 0.1)
				(type default)
			)
			(layer "B.Fab")
		)
		(fp_line
			(start 0.67945 0.3048)
			(end 0.67945 -0.305054)
			(stroke
				(width 0.1)
				(type default)
			)
			(layer "B.Fab")
		)
		(fp_line
			(start 0.12065 0.3048)
			(end 0.67945 0.3048)
			(stroke
				(width 0.1)
				(type default)
			)
			(layer "B.Fab")
		)
		(fp_line
			(start -0.120396 0.3048)
			(end -0.120396 0.2794)
			(stroke
				(width 0.1)
				(type default)
			)
			(layer "B.Fab")
		)
		(fp_line
			(start -0.67945 0.3048)
			(end -0.120396 0.3048)
			(stroke
				(width 0.1)
				(type default)
			)
			(layer "B.Fab")
		)
		(pad "1" smd circle
			(at 0.40005 0 270)
			(size 0 0)
			(layers "B.Cu" "B.Mask" "B.Paste")
			(net "P3V3_AUX")
		)
		(pad "2" smd circle
			(at -0.40005 0 270)
			(size 0 0)
			(layers "B.Cu" "B.Mask" "B.Paste")
			(net "SCM_ROT_CPU_RST_R_N")
		)
	)
	(footprint ""
		(layer "B.Cu")
		(at 342.973406 -416.899344 90)
		(property "Reference" "C6557"
			(at 0 0 90)
			(layer "B.SilkS")
			(hide yes)
			(effects
				(font
					(size 1.27 1.27)
				)
				(justify mirror)
			)
		)
		(property "Value" ""
			(at 0 0 90)
			(layer "B.Fab")
			(effects
				(font
					(size 1.27 1.27)
				)
				(justify mirror)
			)
		)
		(duplicate_pad_numbers_are_jumpers no)
		(fp_line
			(start 0.299974 -0.150114)
			(end -0.299974 -0.150114)
			(stroke
				(width 0.1)
				(type default)
			)
			(layer "B.Fab")
		)
		(fp_line
			(start -0.299974 -0.150114)
			(end -0.299974 0.150114)
			(stroke
				(width 0.1)
				(type default)
			)
			(layer "B.Fab")
		)
		(fp_line
			(start 0.299974 0.150114)
			(end 0.299974 -0.150114)
			(stroke
				(width 0.1)
				(type default)
			)
			(layer "B.Fab")
		)
		(fp_line
			(start -0.299974 0.150114)
			(end 0.299974 0.150114)
			(stroke
				(width 0.1)
				(type default)
			)
			(layer "B.Fab")
		)
		(pad "1" smd rect
			(at 0.2667 0 270)
			(size 0.3048 0.381)
			(layers "B.Cu" "B.Mask" "B.Paste")
			(net "P5E_CPU0_P1_TX_BUF_C_DP<12>")
		)
		(pad "2" smd rect
			(at -0.2667 0 270)
			(size 0.3048 0.381)
			(layers "B.Cu" "B.Mask" "B.Paste")
			(net "P5E_CPU0_P1_TX_BUF_DP<12>")
		)
	)
	(footprint ""
		(layer "B.Cu")
		(at 239.903 -337.312)
		(property "Reference" "R1394"
			(at 0 0 0)
			(layer "B.SilkS")
			(hide yes)
			(effects
				(font
					(size 1.27 1.27)
				)
				(justify mirror)
			)
		)
		(property "Value" ""
			(at 0 0 0)
			(layer "B.Fab")
			(effects
				(font
					(size 1.27 1.27)
				)
				(justify mirror)
			)
		)
		(duplicate_pad_numbers_are_jumpers no)
		(fp_line
			(start -0.32512 -0.175006)
			(end -0.32512 0.175006)
			(stroke
				(width 0.1)
				(type default)
			)
			(layer "B.Fab")
		)
		(fp_line
			(start -0.32512 0.175006)
			(end 0.32512 0.175006)
			(stroke
				(width 0.1)
				(type default)
			)
			(layer "B.Fab")
		)
		(fp_line
			(start 0.32512 -0.175006)
			(end -0.32512 -0.175006)
			(stroke
				(width 0.1)
				(type default)
			)
			(layer "B.Fab")
		)
		(fp_line
			(start 0.32512 0.175006)
			(end 0.32512 -0.175006)
			(stroke
				(width 0.1)
				(type default)
			)
			(layer "B.Fab")
		)
		(pad "1" smd rect
			(at 0.2667 0 180)
			(size 0.3048 0.381)
			(layers "B.Cu" "B.Mask" "B.Paste")
			(net "P1V8_CPU1_RT_1D")
		)
		(pad "2" smd rect
			(at -0.2667 0)
			(size 0.3048 0.381)
			(layers "B.Cu" "B.Mask" "B.Paste")
			(net "SMB_RT_CPU1_P1_ROM_MUX_2D_R_SCL")
		)
	)
)
